(kicad_pcb
	(version 20260206)
	(generator "pcbnew")
	(generator_version "10.0")
	(general
		(thickness 1.6)
		(legacy_teardrops no)
	)
	(paper "A4")
	(title_block
		(title "pdpb — Lightning_PDPB_BRD.brd")
		(comment 1 "Lightning (Wiwynn / Facebook NVMe JBOF) / footprints 904-908 of 1140")
	)
	(layers
		(0 "F.Cu" signal "TOP")
		(4 "In1.Cu" signal "L2GND")
		(6 "In2.Cu" signal "L3")
		(8 "In3.Cu" signal "L4VCC")
		(10 "In4.Cu" signal "L5VCC")
		(12 "In5.Cu" signal "L6")
		(14 "In6.Cu" signal "L7GND")
		(2 "B.Cu" signal "BOTTOM")
		(9 "F.Adhes" user "F.Adhesive")
		(11 "B.Adhes" user "B.Adhesive")
		(13 "F.Paste" user "Package Geometry/Pastemask Top")
		(15 "B.Paste" user "Package Geometry/Pastemask Bottom")
		(5 "F.SilkS" user "Ref Des/Silkscreen Top")
		(7 "B.SilkS" user "Ref Des/Silkscreen Bottom")
		(1 "F.Mask" user "Board Geometry/Soldermask Top")
		(3 "B.Mask" user "Board Geometry/Soldermask Bottom")
		(17 "Dwgs.User" user "User.Drawings")
		(19 "Cmts.User" user "User.Comments")
		(21 "Eco1.User" user "User.Eco1")
		(23 "Eco2.User" user "User.Eco2")
		(25 "Edge.Cuts" user "Board Geometry/Outline")
		(27 "Margin" user)
		(31 "F.CrtYd" user "Package Geometry/Place Bound Top")
		(29 "B.CrtYd" user "Package Geometry/Place Bound Bottom")
		(35 "F.Fab" user "Ref Des/Assembly Top")
		(33 "B.Fab" user "Ref Des/Assembly Bottom")
	)
	(footprint ""
		(layer "F.Cu")
		(at 21.5138 -295.6306)
		(property "Reference" "D25"
			(at 0 0 0)
			(layer "F.SilkS")
			(hide yes)
			(effects
				(font
					(size 1.27 1.27)
				)
			)
		)
		(property "Value" "RB551V30-1-GP"
			(at 0 -6.7818 0)
			(unlocked yes)
			(layer "F.Fab")
			(hide yes)
			(effects
				(font
					(size 1.016 1.016)
					(thickness 0.1524)
				)
			)
		)
		(property "Device Type" "SOD323AKH44"
			(at 0 -8.6868 0)
			(unlocked yes)
			(layer "F.Fab")
			(hide yes)
			(effects
				(font
					(size 1.016 1.016)
					(thickness 0.1524)
				)
			)
		)
		(duplicate_pad_numbers_are_jumpers no)
		(fp_line
			(start -0.889 -1.9304)
			(end 0.889 -1.9304)
			(stroke
				(width 0.1524)
				(type default)
			)
			(layer "F.SilkS")
		)
		(fp_line
			(start -0.889 2.159)
			(end -0.889 -1.9304)
			(stroke
				(width 0.1524)
				(type default)
			)
			(layer "F.SilkS")
		)
		(fp_line
			(start 0.762 2.0574)
			(end -0.762 2.0574)
			(stroke
				(width 0.508)
				(type default)
			)
			(layer "F.SilkS")
		)
		(fp_line
			(start 0.889 -1.9304)
			(end 0.889 2.159)
			(stroke
				(width 0.1524)
				(type default)
			)
			(layer "F.SilkS")
		)
		(fp_line
			(start 0.889 2.159)
			(end -0.889 2.159)
			(stroke
				(width 0.1524)
				(type default)
			)
			(layer "F.SilkS")
		)
		(fp_rect
			(start -1.016 2.3114)
			(end 1.016 -2.0066)
			(stroke
				(width 0)
				(type default)
			)
			(fill no)
			(layer "F.CrtYd")
		)
		(fp_poly
			(pts
				(xy -1.016 -2.0066) (xy 1.016 -2.0066) (xy 1.016 2.3114) (xy -1.016 2.3114)
			)
			(stroke
				(width 0)
				(type default)
			)
			(fill no)
			(layer "F.Fab")
		)
		(pad "A" smd rect
			(at 0 -1.143)
			(size 0.5588 1.016)
			(layers "F.Cu" "F.Mask" "F.Paste")
			(net "SW_SSD7_R")
		)
		(pad "K" smd rect
			(at 0 1.143)
			(size 0.5588 1.016)
			(layers "F.Cu" "F.Mask" "F.Paste")
			(net "SW_SSD7_N")
		)
	)
	(footprint ""
		(layer "F.Cu")
		(at 76.2 -361.061 -90)
		(property "Reference" "EU17"
			(at 0 0 270)
			(layer "F.SilkS")
			(hide yes)
			(effects
				(font
					(size 1.27 1.27)
				)
			)
		)
		(property "Value" "PCA9547BS-GP"
			(at 4.064 -5.5372 270)
			(unlocked yes)
			(layer "F.Fab")
			(hide yes)
			(effects
				(font
					(size 1.016 1.016)
					(thickness 0.1524)
				)
			)
		)
		(property "Device Type" "QFN24-G2D25H40"
			(at 4.064 -7.0612 270)
			(unlocked yes)
			(layer "F.Fab")
			(hide yes)
			(effects
				(font
					(size 1.016 1.016)
					(thickness 0.1524)
				)
			)
		)
		(duplicate_pad_numbers_are_jumpers no)
		(fp_line
			(start -0.254 3.302)
			(end -0.254 2.794)
			(stroke
				(width 0.1524)
				(type default)
			)
			(layer "F.SilkS")
		)
		(fp_line
			(start -3.0226 3.0226)
			(end -1.7526 3.0226)
			(stroke
				(width 0.1524)
				(type default)
			)
			(layer "F.SilkS")
		)
		(fp_line
			(start 1.7526 3.0226)
			(end 3.0226 3.0226)
			(stroke
				(width 0.1524)
				(type default)
			)
			(layer "F.SilkS")
		)
		(fp_line
			(start 3.0226 3.0226)
			(end 3.0226 1.7526)
			(stroke
				(width 0.1524)
				(type default)
			)
			(layer "F.SilkS")
		)
		(fp_line
			(start -3.0226 1.7526)
			(end -3.0226 3.0226)
			(stroke
				(width 0.1524)
				(type default)
			)
			(layer "F.SilkS")
		)
		(fp_line
			(start 2.8194 0.762)
			(end 3.5814 0.762)
			(stroke
				(width 0.1524)
				(type default)
			)
			(layer "F.SilkS")
		)
		(fp_line
			(start -3.5306 0.254)
			(end -2.7686 0.254)
			(stroke
				(width 0.1524)
				(type default)
			)
			(layer "F.SilkS")
		)
		(fp_line
			(start -3.0226 -1.7526)
			(end -3.0226 -3.0226)
			(stroke
				(width 0.1524)
				(type default)
			)
			(layer "F.SilkS")
		)
		(fp_line
			(start -0.7366 -2.794)
			(end -0.7366 -3.302)
			(stroke
				(width 0.1524)
				(type default)
			)
			(layer "F.SilkS")
		)
		(fp_line
			(start -3.0226 -3.0226)
			(end -1.7526 -3.0226)
			(stroke
				(width 0.1524)
				(type default)
			)
			(layer "F.SilkS")
		)
		(fp_poly
			(pts
				(xy 1.7526 -3.0226) (xy 3.0226 -1.7526) (xy 3.0226 -3.0226)
			)
			(stroke
				(width 0)
				(type default)
			)
			(fill yes)
			(layer "F.SilkS")
		)
		(fp_rect
			(start -2.0066 2.0066)
			(end 2.0066 -2.0066)
			(stroke
				(width 0)
				(type default)
			)
			(fill no)
			(layer "F.CrtYd")
		)
		(fp_poly
			(pts
				(xy -2.0066 -2.0066) (xy -2.0066 -3.0226) (xy -3.0226 -3.0226) (xy -3.0226 3.0226) (xy 3.0226 3.0226)
				(xy 3.0226 -3.0226) (xy -2.00152 -3.0226) (xy -2.00152 -2.0066) (xy 2.0066 -2.0066) (xy 2.0066 2.0066)
				(xy -2.0066 2.0066)
			)
			(stroke
				(width 0)
				(type default)
			)
			(fill no)
			(layer "F.CrtYd")
		)
		(fp_rect
			(start -3.0226 3.0226)
			(end 3.0226 -3.0226)
			(stroke
				(width 0)
				(type default)
			)
			(fill no)
			(layer "F.Fab")
		)
		(pad "1" smd rect
			(at 1.249934 -2.0574 270)
			(size 0.3048 0.9144)
			(layers "F.Cu" "F.Mask" "F.Paste")
			(net "SDA_DR2")
		)
		(pad "2" smd rect
			(at 0.750062 -1.9812 270)
			(size 0.3048 1.0668)
			(layers "F.Cu" "F.Mask" "F.Paste")
			(net "SCL_DR2")
		)
		(pad "3" smd rect
			(at 0.249936 -1.9812 270)
			(size 0.3048 1.0668)
			(layers "F.Cu" "F.Mask" "F.Paste")
			(net "SDA_DR1")
		)
		(pad "4" smd rect
			(at -0.249936 -1.9812 270)
			(size 0.3048 1.0668)
			(layers "F.Cu" "F.Mask" "F.Paste")
			(net "SCL_DR1")
		)
		(pad "5" smd rect
			(at -0.750062 -1.9812 270)
			(size 0.3048 1.0668)
			(layers "F.Cu" "F.Mask" "F.Paste")
			(net "SDA_DR0")
		)
		(pad "6" smd rect
			(at -1.249934 -2.0574 270)
			(size 0.3048 0.9144)
			(layers "F.Cu" "F.Mask" "F.Paste")
			(net "SCL_DR0")
		)
		(pad "7" smd rect
			(at -2.0574 -1.249934 270)
			(size 0.9144 0.3048)
			(layers "F.Cu" "F.Mask" "F.Paste")
			(net "SDA_DR5")
		)
		(pad "8" smd rect
			(at -1.9812 -0.750062 270)
			(size 1.0668 0.3048)
			(layers "F.Cu" "F.Mask" "F.Paste")
			(net "SCL_DR5")
		)
		(pad "9" smd rect
			(at -1.9812 -0.249936 270)
			(size 1.0668 0.3048)
			(layers "F.Cu" "F.Mask" "F.Paste")
			(net "GND")
		)
		(pad "10" smd rect
			(at -1.9812 0.249936 270)
			(size 1.0668 0.3048)
			(layers "F.Cu" "F.Mask" "F.Paste")
			(net "SDA_DR10")
		)
		(pad "11" smd rect
			(at -1.9812 0.750062 270)
			(size 1.0668 0.3048)
			(layers "F.Cu" "F.Mask" "F.Paste")
			(net "SCL_DR10")
		)
		(pad "12" smd rect
			(at -2.0574 1.249934 270)
			(size 0.9144 0.3048)
			(layers "F.Cu" "F.Mask" "F.Paste")
			(net "SDA_DR6")
		)
		(pad "13" smd rect
			(at -1.249934 2.0574 270)
			(size 0.3048 0.9144)
			(layers "F.Cu" "F.Mask" "F.Paste")
			(net "SCL_DR6")
		)
		(pad "14" smd rect
			(at -0.750062 1.9812 270)
			(size 0.3048 1.0668)
			(layers "F.Cu" "F.Mask" "F.Paste")
			(net "SDA_DR11")
		)
		(pad "15" smd rect
			(at -0.249936 1.9812 270)
			(size 0.3048 1.0668)
			(layers "F.Cu" "F.Mask" "F.Paste")
			(net "SCL_DR11")
		)
		(pad "16" smd rect
			(at 0.249936 1.9812 270)
			(size 0.3048 1.0668)
			(layers "F.Cu" "F.Mask" "F.Paste")
			(net "SDA_DR7")
		)
		(pad "17" smd rect
			(at 0.750062 1.9812 270)
			(size 0.3048 1.0668)
			(layers "F.Cu" "F.Mask" "F.Paste")
			(net "SCL_DR7")
		)
		(pad "18" smd rect
			(at 1.249934 2.0574 270)
			(size 0.3048 0.9144)
			(layers "F.Cu" "F.Mask" "F.Paste")
			(net "I2C_SW_EU17_ADDRESS_A2")
		)
		(pad "19" smd rect
			(at 2.0574 1.249934 270)
			(size 0.9144 0.3048)
			(layers "F.Cu" "F.Mask" "F.Paste")
			(net "I2C8_SCL_R_SW_EU17")
		)
		(pad "20" smd rect
			(at 1.9812 0.750062 270)
			(size 1.0668 0.3048)
			(layers "F.Cu" "F.Mask" "F.Paste")
			(net "I2C8_SDA_R_SW_EU17")
		)
		(pad "21" smd rect
			(at 1.9812 0.249936 270)
			(size 1.0668 0.3048)
			(layers "F.Cu" "F.Mask" "F.Paste")
			(net "P3V3")
		)
		(pad "22" smd rect
			(at 1.9812 -0.249936 270)
			(size 1.0668 0.3048)
			(layers "F.Cu" "F.Mask" "F.Paste")
			(net "I2C_SW_EU17_ADDRESS_A0")
		)
		(pad "23" smd rect
			(at 1.9812 -0.750062 270)
			(size 1.0668 0.3048)
			(layers "F.Cu" "F.Mask" "F.Paste")
			(net "I2C_SW_EU17_ADDRESS_A1")
		)
		(pad "24" smd rect
			(at 2.0574 -1.249934 270)
			(size 0.9144 0.3048)
			(layers "F.Cu" "F.Mask" "F.Paste")
			(net "I2C_MUX_RESET_R_EU17")
		)
		(pad "25" smd rect
			(at 0 0 270)
			(size 2.2606 2.2606)
			(layers "F.Cu" "F.Mask" "F.Paste")
			(net "GND")
		)
	)
	(footprint ""
		(layer "F.Cu")
		(at 48.387 -7.0104 90)
		(property "Reference" "Q97"
			(at 0 0 90)
			(layer "F.SilkS")
			(hide yes)
			(effects
				(font
					(size 1.27 1.27)
				)
			)
		)
		(property "Value" "2N7002A-7-GP"
			(at 0.127 -8.9662 90)
			(unlocked yes)
			(layer "F.Fab")
			(hide yes)
			(effects
				(font
					(size 1.016 1.016)
					(thickness 0.1524)
				)
			)
		)
		(property "Device Type" "SOT23DGS2D4H48"
			(at 0.127 -10.4902 90)
			(unlocked yes)
			(layer "F.Fab")
			(hide yes)
			(effects
				(font
					(size 1.016 1.016)
					(thickness 0.1524)
				)
			)
		)
		(duplicate_pad_numbers_are_jumpers no)
		(fp_line
			(start 1.651 -1.778)
			(end -1.651 -1.778)
			(stroke
				(width 0.1524)
				(type default)
			)
			(layer "F.SilkS")
		)
		(fp_line
			(start -1.651 -1.778)
			(end -1.651 1.778)
			(stroke
				(width 0.1524)
				(type default)
			)
			(layer "F.SilkS")
		)
		(fp_line
			(start 1.651 1.778)
			(end 1.651 -1.778)
			(stroke
				(width 0.1524)
				(type default)
			)
			(layer "F.SilkS")
		)
		(fp_line
			(start -1.651 1.778)
			(end 1.651 1.778)
			(stroke
				(width 0.1524)
				(type default)
			)
			(layer "F.SilkS")
		)
		(fp_poly
			(pts
				(xy -1.778 1.8796) (xy -1.778 -1.8796) (xy 1.778 -1.8796) (xy 1.778 1.8796)
			)
			(stroke
				(width 0)
				(type default)
			)
			(fill no)
			(layer "F.CrtYd")
		)
		(fp_poly
			(pts
				(xy -1.778 1.8796) (xy -1.778 -1.8796) (xy 1.778 -1.8796) (xy 1.778 1.8796)
			)
			(stroke
				(width 0)
				(type default)
			)
			(fill no)
			(layer "F.Fab")
		)
		(pad "D" smd custom
			(at 0 -0.9525 90)
			(size 0.1905 0.1905)
			(layers "F.Cu" "F.Mask" "F.Paste")
			(net "P12V_MOST14_GATE")
			(options
				(clearance outline)
				(anchor circle)
			)
			(primitives
				(gr_poly
					(pts
						(arc
							(start -0.1778 0.5715)
							(mid -0.321484 0.511984)
							(end -0.381 0.3683)
						)
						(arc
							(start -0.381 -0.3683)
							(mid -0.321484 -0.511984)
							(end -0.1778 -0.5715)
						)
						(arc
							(start 0.1778 -0.5715)
							(mid 0.321484 -0.511984)
							(end 0.381 -0.3683)
						)
						(arc
							(start 0.381 0.3683)
							(mid 0.321484 0.511984)
							(end 0.1778 0.5715)
						)
					)
					(width 0)
					(fill yes)
				)
			)
		)
		(pad "G" smd custom
			(at -0.98425 0.9525 90)
			(size 0.1905 0.1905)
			(layers "F.Cu" "F.Mask" "F.Paste")
			(net "SSD14_PWREN_R")
			(options
				(clearance outline)
				(anchor circle)
			)
			(primitives
				(gr_poly
					(pts
						(arc
							(start -0.1778 0.5715)
							(mid -0.321484 0.511984)
							(end -0.381 0.3683)
						)
						(arc
							(start -0.381 -0.3683)
							(mid -0.321484 -0.511984)
							(end -0.1778 -0.5715)
						)
						(arc
							(start 0.1778 -0.5715)
							(mid 0.321484 -0.511984)
							(end 0.381 -0.3683)
						)
						(arc
							(start 0.381 0.3683)
							(mid 0.321484 0.511984)
							(end 0.1778 0.5715)
						)
					)
					(width 0)
					(fill yes)
				)
			)
		)
		(pad "S" smd custom
			(at 0.98425 0.9525 90)
			(size 0.1905 0.1905)
			(layers "F.Cu" "F.Mask" "F.Paste")
			(net "GND")
			(options
				(clearance outline)
				(anchor circle)
			)
			(primitives
				(gr_poly
					(pts
						(arc
							(start -0.1778 0.5715)
							(mid -0.321484 0.511984)
							(end -0.381 0.3683)
						)
						(arc
							(start -0.381 -0.3683)
							(mid -0.321484 -0.511984)
							(end -0.1778 -0.5715)
						)
						(arc
							(start 0.1778 -0.5715)
							(mid 0.321484 -0.511984)
							(end 0.381 -0.3683)
						)
						(arc
							(start 0.381 0.3683)
							(mid 0.321484 0.511984)
							(end 0.1778 0.5715)
						)
					)
					(width 0)
					(fill yes)
				)
			)
		)
	)
	(footprint ""
		(layer "F.Cu")
		(at 30.988 -374.65)
		(property "Reference" "R340"
			(at 0 0 0)
			(layer "F.SilkS")
			(hide yes)
			(effects
				(font
					(size 1.27 1.27)
				)
			)
		)
		(property "Value" "4K7R2F-GP"
			(at 0.064008 -3.993896 0)
			(unlocked yes)
			(layer "F.Fab")
			(hide yes)
			(effects
				(font
					(size 1.016 1.016)
					(thickness 0.1524)
				)
			)
		)
		(property "Device Type" "R402H16"
			(at 0.064008 -5.517896 0)
			(unlocked yes)
			(layer "F.Fab")
			(hide yes)
			(effects
				(font
					(size 1.016 1.016)
					(thickness 0.1524)
				)
			)
		)
		(duplicate_pad_numbers_are_jumpers no)
		(fp_line
			(start -0.508 -0.9398)
			(end -0.508 0.9398)
			(stroke
				(width 0.1524)
				(type default)
			)
			(layer "F.SilkS")
		)
		(fp_line
			(start 0.508 -0.9398)
			(end -0.508 -0.9398)
			(stroke
				(width 0.1524)
				(type default)
			)
			(layer "F.SilkS")
		)
		(fp_rect
			(start -0.508 0.9398)
			(end 0.508 -0.9398)
			(stroke
				(width 0)
				(type default)
			)
			(fill no)
			(layer "F.CrtYd")
		)
		(fp_rect
			(start -0.508 0.9398)
			(end 0.508 -0.9398)
			(stroke
				(width 0)
				(type default)
			)
			(fill no)
			(layer "F.Fab")
		)
		(pad "1" smd custom
			(at 0 -0.4445)
			(size 0.1397 0.1397)
			(layers "F.Cu" "F.Mask" "F.Paste")
			(net "I2C_B_TMP4_A1")
			(options
				(clearance outline)
				(anchor circle)
			)
			(primitives
				(gr_poly
					(pts
						(arc
							(start -0.1778 -0.2794)
							(mid -0.249642 -0.249642)
							(end -0.2794 -0.1778)
						)
						(arc
							(start -0.2794 0.1778)
							(mid -0.249642 0.249642)
							(end -0.1778 0.2794)
						)
						(arc
							(start 0.1778 0.2794)
							(mid 0.249642 0.249642)
							(end 0.2794 0.1778)
						)
						(arc
							(start 0.2794 -0.1778)
							(mid 0.249642 -0.249642)
							(end 0.1778 -0.2794)
						)
					)
					(width 0)
					(fill yes)
				)
			)
		)
		(pad "2" smd custom
			(at 0 0.4445)
			(size 0.1397 0.1397)
			(layers "F.Cu" "F.Mask" "F.Paste")
			(net "GND")
			(options
				(clearance outline)
				(anchor circle)
			)
			(primitives
				(gr_poly
					(pts
						(arc
							(start -0.1778 -0.2794)
							(mid -0.249642 -0.249642)
							(end -0.2794 -0.1778)
						)
						(arc
							(start -0.2794 0.1778)
							(mid -0.249642 0.249642)
							(end -0.1778 0.2794)
						)
						(arc
							(start 0.1778 0.2794)
							(mid 0.249642 0.249642)
							(end 0.2794 0.1778)
						)
						(arc
							(start 0.2794 -0.1778)
							(mid 0.249642 -0.249642)
							(end 0.1778 -0.2794)
						)
					)
					(width 0)
					(fill yes)
				)
			)
		)
	)
	(footprint ""
		(layer "F.Cu")
		(at 29.7688 -294.9956 -90)
		(property "Reference" "U16"
			(at 0 0 270)
			(layer "F.SilkS")
			(hide yes)
			(effects
				(font
					(size 1.27 1.27)
				)
			)
		)
		(property "Value" "P2003EVG-GP"
			(at 0 -11.1252 270)
			(unlocked yes)
			(layer "F.Fab")
			(hide yes)
			(effects
				(font
					(size 1.016 1.016)
					(thickness 0.1524)
				)
			)
		)
		(property "Device Type" "SOIC8H79"
			(at 0 -12.6492 270)
			(unlocked yes)
			(layer "F.Fab")
			(hide yes)
			(effects
				(font
					(size 1.016 1.016)
					(thickness 0.1524)
				)
			)
		)
		(duplicate_pad_numbers_are_jumpers no)
		(fp_line
			(start -2.6162 3.429)
			(end -2.6162 1.4732)
			(stroke
				(width 0.4064)
				(type default)
			)
			(layer "F.SilkS")
		)
		(fp_line
			(start -2.7432 1.4224)
			(end 2.1336 1.4224)
			(stroke
				(width 0.1524)
				(type default)
			)
			(layer "F.SilkS")
		)
		(fp_line
			(start 2.1336 1.4224)
			(end 2.1336 -1.4224)
			(stroke
				(width 0.1524)
				(type default)
			)
			(layer "F.SilkS")
		)
		(fp_line
			(start -2.2352 0)
			(end -2.7432 0.508)
			(stroke
				(width 0.1524)
				(type default)
			)
			(layer "F.SilkS")
		)
		(fp_line
			(start -2.7432 -0.508)
			(end -2.2352 0)
			(stroke
				(width 0.1524)
				(type default)
			)
			(layer "F.SilkS")
		)
		(fp_line
			(start -2.7432 -1.4224)
			(end -2.7432 1.4224)
			(stroke
				(width 0.1524)
				(type default)
			)
			(layer "F.SilkS")
		)
		(fp_line
			(start 2.1336 -1.4224)
			(end -2.7432 -1.4224)
			(stroke
				(width 0.1524)
				(type default)
			)
			(layer "F.SilkS")
		)
		(fp_poly
			(pts
				(xy 2.2098 -1.4224) (xy 2.2098 1.4224) (xy -2.2225 1.4224) (xy -2.2225 -1.4224)
			)
			(stroke
				(width 0)
				(type default)
			)
			(fill yes)
			(layer "F.SilkS")
		)
		(fp_rect
			(start -2.4511 2.9972)
			(end 2.4511 -2.9972)
			(stroke
				(width 0)
				(type default)
			)
			(fill no)
			(layer "F.CrtYd")
		)
		(fp_poly
			(pts
				(xy -2.8194 3.6322) (xy -2.8194 -3.6322) (xy 2.8194 -3.6322) (xy 2.8194 -2.2987) (xy 2.4511 -2.2987)
				(xy 2.4511 -2.9972) (xy -2.4511 -2.9972) (xy -2.4511 2.9972) (xy 2.4511 2.9972) (xy 2.4511 -2.286)
				(xy 2.8194 -2.286) (xy 2.8194 3.6322)
			)
			(stroke
				(width 0)
				(type default)
			)
			(fill no)
			(layer "F.CrtYd")
		)
		(fp_rect
			(start -2.8194 3.6322)
			(end 2.8194 -3.6322)
			(stroke
				(width 0)
				(type default)
			)
			(fill no)
			(layer "F.Fab")
		)
		(pad "1" smd rect
			(at -1.905 2.54 270)
			(size 0.635 1.651)
			(layers "F.Cu" "F.Mask" "F.Paste")
			(net "P12V")
		)
		(pad "2" smd rect
			(at -0.635 2.54 270)
			(size 0.635 1.651)
			(layers "F.Cu" "F.Mask" "F.Paste")
			(net "P12V")
		)
		(pad "3" smd rect
			(at 0.635 2.54 270)
			(size 0.635 1.651)
			(layers "F.Cu" "F.Mask" "F.Paste")
			(net "P12V")
		)
		(pad "4" smd rect
			(at 1.905 2.54 270)
			(size 0.635 1.651)
			(layers "F.Cu" "F.Mask" "F.Paste")
			(net "SW_SSD7_N")
		)
		(pad "5" smd rect
			(at 1.905 -2.54 270)
			(size 0.635 1.651)
			(layers "F.Cu" "F.Mask" "F.Paste")
			(net "P12V_SSD7")
		)
		(pad "6" smd rect
			(at 0.635 -2.54 270)
			(size 0.635 1.651)
			(layers "F.Cu" "F.Mask" "F.Paste")
			(net "P12V_SSD7")
		)
		(pad "7" smd rect
			(at -0.635 -2.54 270)
			(size 0.635 1.651)
			(layers "F.Cu" "F.Mask" "F.Paste")
			(net "P12V_SSD7")
		)
		(pad "8" smd rect
			(at -1.905 -2.54 270)
			(size 0.635 1.651)
			(layers "F.Cu" "F.Mask" "F.Paste")
			(net "P12V_SSD7")
		)
	)
)
